(kicad_pcb
	(version 20260206)
	(generator "pcbnew")
	(generator_version "10.0")
	(general
		(thickness 1.6)
		(legacy_teardrops no)
	)
	(paper "A4")
	(title_block
		(title "04192023_DAF0TMB3IC0_F0TG_MB_C_brd_V02_OCP.brd")
		(comment 1 "Grand Teton / footprints 6426-6432 of 8354")
	)
	(layers
		(0 "F.Cu" signal "TOP")
		(4 "In1.Cu" signal "GND")
		(6 "In2.Cu" signal "IN1")
		(8 "In3.Cu" signal "GND1")
		(10 "In4.Cu" signal "IN2")
		(12 "In5.Cu" signal "GND2")
		(14 "In6.Cu" signal "IN3")
		(16 "In7.Cu" signal "GND3")
		(18 "In8.Cu" signal "VCC")
		(20 "In9.Cu" signal "VCC1")
		(22 "In10.Cu" signal "GND4")
		(24 "In11.Cu" signal "IN4")
		(26 "In12.Cu" signal "GND5")
		(28 "In13.Cu" signal "IN5")
		(30 "In14.Cu" signal "GND6")
		(32 "In15.Cu" signal "IN6")
		(34 "In16.Cu" signal "GND7")
		(2 "B.Cu" signal "BOTTOM")
		(9 "F.Adhes" user "F.Adhesive")
		(11 "B.Adhes" user "B.Adhesive")
		(13 "F.Paste" user "Package Geometry/Pastemask Top")
		(15 "B.Paste" user "Package Geometry/Pastemask Bottom")
		(5 "F.SilkS" user "Ref Des/Silkscreen Top")
		(7 "B.SilkS" user "Ref Des/Silkscreen Bottom")
		(1 "F.Mask" user "Board Geometry/Soldermask Top")
		(3 "B.Mask" user "Board Geometry/Soldermask Bottom")
		(17 "Dwgs.User" user "User.Drawings")
		(19 "Cmts.User" user "User.Comments")
		(21 "Eco1.User" user "User.Eco1")
		(23 "Eco2.User" user "User.Eco2")
		(25 "Edge.Cuts" user "Board Geometry/Outline")
		(27 "Margin" user)
		(31 "F.CrtYd" user "Package Geometry/Place Bound Top")
		(29 "B.CrtYd" user "Package Geometry/Place Bound Bottom")
		(35 "F.Fab" user "Ref Des/Assembly Top")
		(33 "B.Fab" user "Ref Des/Assembly Bottom")
	)
	(footprint ""
		(layer "B.Cu")
		(at 111.800386 -247.971564 90)
		(property "Reference" "C2341"
			(at 0 0 90)
			(layer "B.SilkS")
			(hide yes)
			(effects
				(font
					(size 1.27 1.27)
				)
				(justify mirror)
			)
		)
		(property "Value" ""
			(at 0 0 90)
			(layer "B.Fab")
			(effects
				(font
					(size 1.27 1.27)
				)
				(justify mirror)
			)
		)
		(duplicate_pad_numbers_are_jumpers no)
		(fp_line
			(start 0.7874 -0.4064)
			(end -0.7874 -0.4064)
			(stroke
				(width 0.1524)
				(type default)
			)
			(layer "B.SilkS")
		)
		(fp_line
			(start -0.7874 -0.4064)
			(end -0.7874 0.4064)
			(stroke
				(width 0.1524)
				(type default)
			)
			(layer "B.SilkS")
		)
		(fp_line
			(start 0.7874 0.4064)
			(end 0.7874 -0.4064)
			(stroke
				(width 0.1524)
				(type default)
			)
			(layer "B.SilkS")
		)
		(fp_line
			(start -0.7874 0.4064)
			(end 0.7874 0.4064)
			(stroke
				(width 0.1524)
				(type default)
			)
			(layer "B.SilkS")
		)
		(fp_line
			(start 0.67945 -0.305054)
			(end 0.12065 -0.305054)
			(stroke
				(width 0.1)
				(type default)
			)
			(layer "B.Fab")
		)
		(fp_line
			(start 0.12065 -0.305054)
			(end 0.12065 -0.2794)
			(stroke
				(width 0.1)
				(type default)
			)
			(layer "B.Fab")
		)
		(fp_line
			(start -0.12065 -0.3048)
			(end -0.67945 -0.3048)
			(stroke
				(width 0.1)
				(type default)
			)
			(layer "B.Fab")
		)
		(fp_line
			(start -0.67945 -0.3048)
			(end -0.67945 0.3048)
			(stroke
				(width 0.1)
				(type default)
			)
			(layer "B.Fab")
		)
		(fp_line
			(start 0.12065 -0.2794)
			(end -0.12065 -0.2794)
			(stroke
				(width 0.1)
				(type default)
			)
			(layer "B.Fab")
		)
		(fp_line
			(start -0.12065 -0.2794)
			(end -0.12065 -0.3048)
			(stroke
				(width 0.1)
				(type default)
			)
			(layer "B.Fab")
		)
		(fp_line
			(start 0.12065 0.2794)
			(end 0.12065 0.3048)
			(stroke
				(width 0.1)
				(type default)
			)
			(layer "B.Fab")
		)
		(fp_line
			(start -0.120396 0.2794)
			(end 0.12065 0.2794)
			(stroke
				(width 0.1)
				(type default)
			)
			(layer "B.Fab")
		)
		(fp_line
			(start 0.67945 0.3048)
			(end 0.67945 -0.305054)
			(stroke
				(width 0.1)
				(type default)
			)
			(layer "B.Fab")
		)
		(fp_line
			(start 0.12065 0.3048)
			(end 0.67945 0.3048)
			(stroke
				(width 0.1)
				(type default)
			)
			(layer "B.Fab")
		)
		(fp_line
			(start -0.120396 0.3048)
			(end -0.120396 0.2794)
			(stroke
				(width 0.1)
				(type default)
			)
			(layer "B.Fab")
		)
		(fp_line
			(start -0.67945 0.3048)
			(end -0.120396 0.3048)
			(stroke
				(width 0.1)
				(type default)
			)
			(layer "B.Fab")
		)
		(pad "1" smd circle
			(at 0.40005 0 270)
			(size 0 0)
			(layers "B.Cu" "B.Mask" "B.Paste")
			(net "PVDDCR_CPU0_P1")
		)
		(pad "2" smd circle
			(at -0.40005 0 270)
			(size 0 0)
			(layers "B.Cu" "B.Mask" "B.Paste")
			(net "GND")
		)
	)
	(footprint ""
		(layer "B.Cu")
		(at 239.903 -341.884)
		(property "Reference" "R1407"
			(at 0 0 0)
			(layer "B.SilkS")
			(hide yes)
			(effects
				(font
					(size 1.27 1.27)
				)
				(justify mirror)
			)
		)
		(property "Value" ""
			(at 0 0 0)
			(layer "B.Fab")
			(effects
				(font
					(size 1.27 1.27)
				)
				(justify mirror)
			)
		)
		(duplicate_pad_numbers_are_jumpers no)
		(fp_line
			(start -0.32512 -0.175006)
			(end -0.32512 0.175006)
			(stroke
				(width 0.1)
				(type default)
			)
			(layer "B.Fab")
		)
		(fp_line
			(start -0.32512 0.175006)
			(end 0.32512 0.175006)
			(stroke
				(width 0.1)
				(type default)
			)
			(layer "B.Fab")
		)
		(fp_line
			(start 0.32512 -0.175006)
			(end -0.32512 -0.175006)
			(stroke
				(width 0.1)
				(type default)
			)
			(layer "B.Fab")
		)
		(fp_line
			(start 0.32512 0.175006)
			(end 0.32512 -0.175006)
			(stroke
				(width 0.1)
				(type default)
			)
			(layer "B.Fab")
		)
		(pad "1" smd rect
			(at 0.2667 0 180)
			(size 0.3048 0.381)
			(layers "B.Cu" "B.Mask" "B.Paste")
			(net "P1V8_CPU1_RT_1D")
		)
		(pad "2" smd rect
			(at -0.2667 0)
			(size 0.3048 0.381)
			(layers "B.Cu" "B.Mask" "B.Paste")
			(net "SMB_RT_CPU1_P2_ROM_MUX_2D_R_SCL")
		)
	)
	(footprint ""
		(layer "B.Cu")
		(at 139.152376 -386.745988 -90)
		(property "Reference" "C439"
			(at 0 0 90)
			(layer "B.SilkS")
			(hide yes)
			(effects
				(font
					(size 1.27 1.27)
				)
				(justify mirror)
			)
		)
		(property "Value" ""
			(at 0 0 90)
			(layer "B.Fab")
			(effects
				(font
					(size 1.27 1.27)
				)
				(justify mirror)
			)
		)
		(duplicate_pad_numbers_are_jumpers no)
		(fp_line
			(start -0.7874 0.4064)
			(end 0.7874 0.4064)
			(stroke
				(width 0.1524)
				(type default)
			)
			(layer "B.SilkS")
		)
		(fp_line
			(start 0.7874 0.4064)
			(end 0.7874 -0.4064)
			(stroke
				(width 0.1524)
				(type default)
			)
			(layer "B.SilkS")
		)
		(fp_line
			(start -0.7874 -0.4064)
			(end -0.7874 0.4064)
			(stroke
				(width 0.1524)
				(type default)
			)
			(layer "B.SilkS")
		)
		(fp_line
			(start 0.7874 -0.4064)
			(end -0.7874 -0.4064)
			(stroke
				(width 0.1524)
				(type default)
			)
			(layer "B.SilkS")
		)
		(fp_line
			(start -0.67945 0.3048)
			(end -0.120396 0.3048)
			(stroke
				(width 0.1)
				(type default)
			)
			(layer "B.Fab")
		)
		(fp_line
			(start -0.120396 0.3048)
			(end -0.120396 0.2794)
			(stroke
				(width 0.1)
				(type default)
			)
			(layer "B.Fab")
		)
		(fp_line
			(start 0.12065 0.3048)
			(end 0.67945 0.3048)
			(stroke
				(width 0.1)
				(type default)
			)
			(layer "B.Fab")
		)
		(fp_line
			(start 0.67945 0.3048)
			(end 0.67945 -0.305054)
			(stroke
				(width 0.1)
				(type default)
			)
			(layer "B.Fab")
		)
		(fp_line
			(start -0.120396 0.2794)
			(end 0.12065 0.2794)
			(stroke
				(width 0.1)
				(type default)
			)
			(layer "B.Fab")
		)
		(fp_line
			(start 0.12065 0.2794)
			(end 0.12065 0.3048)
			(stroke
				(width 0.1)
				(type default)
			)
			(layer "B.Fab")
		)
		(fp_line
			(start -0.12065 -0.2794)
			(end -0.12065 -0.3048)
			(stroke
				(width 0.1)
				(type default)
			)
			(layer "B.Fab")
		)
		(fp_line
			(start 0.12065 -0.2794)
			(end -0.12065 -0.2794)
			(stroke
				(width 0.1)
				(type default)
			)
			(layer "B.Fab")
		)
		(fp_line
			(start -0.67945 -0.3048)
			(end -0.67945 0.3048)
			(stroke
				(width 0.1)
				(type default)
			)
			(layer "B.Fab")
		)
		(fp_line
			(start -0.12065 -0.3048)
			(end -0.67945 -0.3048)
			(stroke
				(width 0.1)
				(type default)
			)
			(layer "B.Fab")
		)
		(fp_line
			(start 0.12065 -0.305054)
			(end 0.12065 -0.2794)
			(stroke
				(width 0.1)
				(type default)
			)
			(layer "B.Fab")
		)
		(fp_line
			(start 0.67945 -0.305054)
			(end 0.12065 -0.305054)
			(stroke
				(width 0.1)
				(type default)
			)
			(layer "B.Fab")
		)
		(pad "1" smd circle
			(at 0.40005 0 90)
			(size 0 0)
			(layers "B.Cu" "B.Mask" "B.Paste")
			(net "P1V8_CPU1_RT_1D")
		)
		(pad "2" smd circle
			(at -0.40005 0 90)
			(size 0 0)
			(layers "B.Cu" "B.Mask" "B.Paste")
			(net "GND")
		)
	)
	(footprint ""
		(layer "B.Cu")
		(at 182.880254 -424.39082)
		(property "Reference" "R6234"
			(at 0 0 0)
			(layer "B.SilkS")
			(hide yes)
			(effects
				(font
					(size 1.27 1.27)
				)
				(justify mirror)
			)
		)
		(property "Value" ""
			(at 0 0 0)
			(layer "B.Fab")
			(effects
				(font
					(size 1.27 1.27)
				)
				(justify mirror)
			)
		)
		(duplicate_pad_numbers_are_jumpers no)
		(fp_line
			(start -0.7874 -0.4064)
			(end -0.7874 0.4064)
			(stroke
				(width 0.1524)
				(type default)
			)
			(layer "B.SilkS")
		)
		(fp_line
			(start -0.7874 0.4064)
			(end 0.7874 0.4064)
			(stroke
				(width 0.1524)
				(type default)
			)
			(layer "B.SilkS")
		)
		(fp_line
			(start 0.7874 -0.4064)
			(end -0.7874 -0.4064)
			(stroke
				(width 0.1524)
				(type default)
			)
			(layer "B.SilkS")
		)
		(fp_line
			(start 0.7874 0.4064)
			(end 0.7874 -0.4064)
			(stroke
				(width 0.1524)
				(type default)
			)
			(layer "B.SilkS")
		)
		(fp_line
			(start -0.67945 -0.3048)
			(end -0.67945 0.3048)
			(stroke
				(width 0.1)
				(type default)
			)
			(layer "B.Fab")
		)
		(fp_line
			(start -0.67945 0.3048)
			(end -0.120396 0.3048)
			(stroke
				(width 0.1)
				(type default)
			)
			(layer "B.Fab")
		)
		(fp_line
			(start -0.12065 -0.3048)
			(end -0.67945 -0.3048)
			(stroke
				(width 0.1)
				(type default)
			)
			(layer "B.Fab")
		)
		(fp_line
			(start -0.12065 -0.2794)
			(end -0.12065 -0.3048)
			(stroke
				(width 0.1)
				(type default)
			)
			(layer "B.Fab")
		)
		(fp_line
			(start -0.120396 0.2794)
			(end 0.12065 0.2794)
			(stroke
				(width 0.1)
				(type default)
			)
			(layer "B.Fab")
		)
		(fp_line
			(start -0.120396 0.3048)
			(end -0.120396 0.2794)
			(stroke
				(width 0.1)
				(type default)
			)
			(layer "B.Fab")
		)
		(fp_line
			(start 0.12065 -0.305054)
			(end 0.12065 -0.2794)
			(stroke
				(width 0.1)
				(type default)
			)
			(layer "B.Fab")
		)
		(fp_line
			(start 0.12065 -0.2794)
			(end -0.12065 -0.2794)
			(stroke
				(width 0.1)
				(type default)
			)
			(layer "B.Fab")
		)
		(fp_line
			(start 0.12065 0.2794)
			(end 0.12065 0.3048)
			(stroke
				(width 0.1)
				(type default)
			)
			(layer "B.Fab")
		)
		(fp_line
			(start 0.12065 0.3048)
			(end 0.67945 0.3048)
			(stroke
				(width 0.1)
				(type default)
			)
			(layer "B.Fab")
		)
		(fp_line
			(start 0.67945 -0.305054)
			(end 0.12065 -0.305054)
			(stroke
				(width 0.1)
				(type default)
			)
			(layer "B.Fab")
		)
		(fp_line
			(start 0.67945 0.3048)
			(end 0.67945 -0.305054)
			(stroke
				(width 0.1)
				(type default)
			)
			(layer "B.Fab")
		)
		(pad "1" smd circle
			(at 0.40005 0 180)
			(size 0 0)
			(layers "B.Cu" "B.Mask" "B.Paste")
			(net "HSC_CSOUT")
		)
		(pad "2" smd circle
			(at -0.40005 0 180)
			(size 0 0)
			(layers "B.Cu" "B.Mask" "B.Paste")
			(net "A_HSC_HIGH")
		)
	)
	(footprint ""
		(layer "B.Cu")
		(at 52.782978 -433.682902 -90)
		(property "Reference" "R3428"
			(at 0 0 90)
			(layer "B.SilkS")
			(hide yes)
			(effects
				(font
					(size 1.27 1.27)
				)
				(justify mirror)
			)
		)
		(property "Value" ""
			(at 0 0 90)
			(layer "B.Fab")
			(effects
				(font
					(size 1.27 1.27)
				)
				(justify mirror)
			)
		)
		(duplicate_pad_numbers_are_jumpers no)
		(fp_line
			(start -0.7874 0.4064)
			(end 0.7874 0.4064)
			(stroke
				(width 0.1524)
				(type default)
			)
			(layer "B.SilkS")
		)
		(fp_line
			(start 0.7874 0.4064)
			(end 0.7874 -0.4064)
			(stroke
				(width 0.1524)
				(type default)
			)
			(layer "B.SilkS")
		)
		(fp_line
			(start -0.7874 -0.4064)
			(end -0.7874 0.4064)
			(stroke
				(width 0.1524)
				(type default)
			)
			(layer "B.SilkS")
		)
		(fp_line
			(start 0.7874 -0.4064)
			(end -0.7874 -0.4064)
			(stroke
				(width 0.1524)
				(type default)
			)
			(layer "B.SilkS")
		)
		(fp_line
			(start -0.67945 0.3048)
			(end -0.120396 0.3048)
			(stroke
				(width 0.1)
				(type default)
			)
			(layer "B.Fab")
		)
		(fp_line
			(start -0.120396 0.3048)
			(end -0.120396 0.2794)
			(stroke
				(width 0.1)
				(type default)
			)
			(layer "B.Fab")
		)
		(fp_line
			(start 0.12065 0.3048)
			(end 0.67945 0.3048)
			(stroke
				(width 0.1)
				(type default)
			)
			(layer "B.Fab")
		)
		(fp_line
			(start 0.67945 0.3048)
			(end 0.67945 -0.305054)
			(stroke
				(width 0.1)
				(type default)
			)
			(layer "B.Fab")
		)
		(fp_line
			(start -0.120396 0.2794)
			(end 0.12065 0.2794)
			(stroke
				(width 0.1)
				(type default)
			)
			(layer "B.Fab")
		)
		(fp_line
			(start 0.12065 0.2794)
			(end 0.12065 0.3048)
			(stroke
				(width 0.1)
				(type default)
			)
			(layer "B.Fab")
		)
		(fp_line
			(start -0.12065 -0.2794)
			(end -0.12065 -0.3048)
			(stroke
				(width 0.1)
				(type default)
			)
			(layer "B.Fab")
		)
		(fp_line
			(start 0.12065 -0.2794)
			(end -0.12065 -0.2794)
			(stroke
				(width 0.1)
				(type default)
			)
			(layer "B.Fab")
		)
		(fp_line
			(start -0.67945 -0.3048)
			(end -0.67945 0.3048)
			(stroke
				(width 0.1)
				(type default)
			)
			(layer "B.Fab")
		)
		(fp_line
			(start -0.12065 -0.3048)
			(end -0.67945 -0.3048)
			(stroke
				(width 0.1)
				(type default)
			)
			(layer "B.Fab")
		)
		(fp_line
			(start 0.12065 -0.305054)
			(end 0.12065 -0.2794)
			(stroke
				(width 0.1)
				(type default)
			)
			(layer "B.Fab")
		)
		(fp_line
			(start 0.67945 -0.305054)
			(end 0.12065 -0.305054)
			(stroke
				(width 0.1)
				(type default)
			)
			(layer "B.Fab")
		)
		(pad "1" smd circle
			(at 0.40005 0 90)
			(size 0 0)
			(layers "B.Cu" "B.Mask" "B.Paste")
			(net "GPU_FPGA_THERM_OVERT_N")
		)
		(pad "2" smd circle
			(at -0.40005 0 90)
			(size 0 0)
			(layers "B.Cu" "B.Mask" "B.Paste")
			(net "GND")
		)
	)
	(footprint ""
		(layer "B.Cu")
		(at 208.461356 -385.136136)
		(property "Reference" "PR2511"
			(at 0 0 0)
			(layer "B.SilkS")
			(hide yes)
			(effects
				(font
					(size 1.27 1.27)
				)
				(justify mirror)
			)
		)
		(property "Value" ""
			(at 0 0 0)
			(layer "B.Fab")
			(effects
				(font
					(size 1.27 1.27)
				)
				(justify mirror)
			)
		)
		(duplicate_pad_numbers_are_jumpers no)
		(fp_line
			(start -0.7874 -0.4064)
			(end -0.7874 0.4064)
			(stroke
				(width 0.1524)
				(type default)
			)
			(layer "B.SilkS")
		)
		(fp_line
			(start -0.7874 0.4064)
			(end 0.7874 0.4064)
			(stroke
				(width 0.1524)
				(type default)
			)
			(layer "B.SilkS")
		)
		(fp_line
			(start 0.7874 -0.4064)
			(end -0.7874 -0.4064)
			(stroke
				(width 0.1524)
				(type default)
			)
			(layer "B.SilkS")
		)
		(fp_line
			(start 0.7874 0.4064)
			(end 0.7874 -0.4064)
			(stroke
				(width 0.1524)
				(type default)
			)
			(layer "B.SilkS")
		)
		(fp_line
			(start -0.67945 -0.3048)
			(end -0.67945 0.3048)
			(stroke
				(width 0.1)
				(type default)
			)
			(layer "B.Fab")
		)
		(fp_line
			(start -0.67945 0.3048)
			(end -0.120396 0.3048)
			(stroke
				(width 0.1)
				(type default)
			)
			(layer "B.Fab")
		)
		(fp_line
			(start -0.12065 -0.3048)
			(end -0.67945 -0.3048)
			(stroke
				(width 0.1)
				(type default)
			)
			(layer "B.Fab")
		)
		(fp_line
			(start -0.12065 -0.2794)
			(end -0.12065 -0.3048)
			(stroke
				(width 0.1)
				(type default)
			)
			(layer "B.Fab")
		)
		(fp_line
			(start -0.120396 0.2794)
			(end 0.12065 0.2794)
			(stroke
				(width 0.1)
				(type default)
			)
			(layer "B.Fab")
		)
		(fp_line
			(start -0.120396 0.3048)
			(end -0.120396 0.2794)
			(stroke
				(width 0.1)
				(type default)
			)
			(layer "B.Fab")
		)
		(fp_line
			(start 0.12065 -0.305054)
			(end 0.12065 -0.2794)
			(stroke
				(width 0.1)
				(type default)
			)
			(layer "B.Fab")
		)
		(fp_line
			(start 0.12065 -0.2794)
			(end -0.12065 -0.2794)
			(stroke
				(width 0.1)
				(type default)
			)
			(layer "B.Fab")
		)
		(fp_line
			(start 0.12065 0.2794)
			(end 0.12065 0.3048)
			(stroke
				(width 0.1)
				(type default)
			)
			(layer "B.Fab")
		)
		(fp_line
			(start 0.12065 0.3048)
			(end 0.67945 0.3048)
			(stroke
				(width 0.1)
				(type default)
			)
			(layer "B.Fab")
		)
		(fp_line
			(start 0.67945 -0.305054)
			(end 0.12065 -0.305054)
			(stroke
				(width 0.1)
				(type default)
			)
			(layer "B.Fab")
		)
		(fp_line
			(start 0.67945 0.3048)
			(end 0.67945 -0.305054)
			(stroke
				(width 0.1)
				(type default)
			)
			(layer "B.Fab")
		)
		(pad "1" smd circle
			(at 0.40005 0 180)
			(size 0 0)
			(layers "B.Cu" "B.Mask" "B.Paste")
			(net "P12V_HSC_ADC_P")
		)
		(pad "2" smd circle
			(at -0.40005 0 180)
			(size 0 0)
			(layers "B.Cu" "B.Mask" "B.Paste")
			(net "P12V_HSC_SENSE2_R2_P")
		)
	)
	(footprint ""
		(layer "B.Cu")
		(at 154.206194 -386.766562 90)
		(property "Reference" "C381"
			(at 0 0 90)
			(layer "B.SilkS")
			(hide yes)
			(effects
				(font
					(size 1.27 1.27)
				)
				(justify mirror)
			)
		)
		(property "Value" ""
			(at 0 0 90)
			(layer "B.Fab")
			(effects
				(font
					(size 1.27 1.27)
				)
				(justify mirror)
			)
		)
		(duplicate_pad_numbers_are_jumpers no)
		(fp_line
			(start 0.299974 -0.150114)
			(end -0.299974 -0.150114)
			(stroke
				(width 0.1)
				(type default)
			)
			(layer "B.Fab")
		)
		(fp_line
			(start -0.299974 -0.150114)
			(end -0.299974 0.150114)
			(stroke
				(width 0.1)
				(type default)
			)
			(layer "B.Fab")
		)
		(fp_line
			(start 0.299974 0.150114)
			(end 0.299974 -0.150114)
			(stroke
				(width 0.1)
				(type default)
			)
			(layer "B.Fab")
		)
		(fp_line
			(start -0.299974 0.150114)
			(end 0.299974 0.150114)
			(stroke
				(width 0.1)
				(type default)
			)
			(layer "B.Fab")
		)
		(pad "1" smd rect
			(at 0.2667 0 270)
			(size 0.3048 0.381)
			(layers "B.Cu" "B.Mask" "B.Paste")
			(net "P1V8_CPU1_RT2_1A")
		)
		(pad "2" smd rect
			(at -0.2667 0 270)
			(size 0.3048 0.381)
			(layers "B.Cu" "B.Mask" "B.Paste")
			(net "GND")
		)
	)
)
